(kicad_pcb
	(version 20241229)
	(generator "pcbnew")
	(generator_version "9.0")
	(general
		(thickness 1.62)
		(legacy_teardrops no)
	)
	(paper "A3")
	(title_block
		(title "COM Express 7 Baseboard")
		(date "2025-02-04")
		(rev "1.1.2")
		(company "Antmicro Ltd")
		(comment 1 "www.antmicro.com")
		(comment 9 "footprints 303-305 of 802")
	)
	(layers
		(0 "F.Cu" signal)
		(4 "In1.Cu" signal)
		(6 "In2.Cu" signal)
		(8 "In3.Cu" signal)
		(10 "In4.Cu" signal)
		(12 "In5.Cu" signal)
		(14 "In6.Cu" signal)
		(2 "B.Cu" signal)
		(9 "F.Adhes" user "F.Adhesive")
		(11 "B.Adhes" user "B.Adhesive")
		(13 "F.Paste" user)
		(15 "B.Paste" user)
		(5 "F.SilkS" user "F.Silkscreen")
		(7 "B.SilkS" user "B.Silkscreen")
		(1 "F.Mask" user)
		(3 "B.Mask" user)
		(17 "Dwgs.User" user "User.Drawings")
		(19 "Cmts.User" user "User.Comments")
		(21 "Eco1.User" user "User.Eco1")
		(23 "Eco2.User" user "User.Eco2")
		(25 "Edge.Cuts" user)
		(27 "Margin" user)
		(31 "F.CrtYd" user "F.Courtyard")
		(29 "B.CrtYd" user "B.Courtyard")
		(35 "F.Fab" user)
		(33 "B.Fab" user)
	)
	(footprint "antmicro-footprints:Spacer_Drill3.7mm_H2.5mm_9774025151R"
		(layer "F.Cu")
		(at 261.75 102.11)
		(descr "Spacer M=3 h=2.5mm fi=5.1mm")
		(property "Reference" "H2"
			(at 0 -3.2 0)
			(layer "F.SilkS")
			(hide yes)
			(effects
				(font
					(size 0.7 0.7)
					(thickness 0.15)
				)
				(justify left bottom)
			)
		)
		(property "Value" "Spacer_Drill3.7mm_H2.5mm_9774025151R"
			(at 0 4 0)
			(layer "F.Fab")
			(effects
				(font
					(size 0.7 0.7)
					(thickness 0.15)
				)
				(justify left bottom)
			)
		)
		(property "Datasheet" "https://www.we-online.com/components/products/datasheet/9774025151R.pdf"
			(at 0 0 0)
			(layer "F.Fab")
			(hide yes)
			(effects
				(font
					(size 1.27 1.27)
					(thickness 0.15)
				)
			)
		)
		(property "Author" "Antmicro"
			(at 0 0 0)
			(layer "F.Fab")
			(hide yes)
			(effects
				(font
					(size 1 1)
					(thickness 0.15)
				)
			)
		)
		(property "License" "Apache-2.0"
			(at 0 0 0)
			(layer "F.Fab")
			(hide yes)
			(effects
				(font
					(size 1 1)
					(thickness 0.15)
				)
			)
		)
		(property "MPN" "9774025151R"
			(at 0 0 0)
			(layer "F.Fab")
			(hide yes)
			(effects
				(font
					(size 1 1)
					(thickness 0.15)
				)
			)
		)
		(property "Manufacturer" "Würth Elektronik"
			(at 0 0 0)
			(layer "F.Fab")
			(hide yes)
			(effects
				(font
					(size 1 1)
					(thickness 0.15)
				)
			)
		)
		(property "Public" "False"
			(at 0 0 0)
			(layer "F.Fab")
			(hide yes)
			(effects
				(font
					(size 1 1)
					(thickness 0.15)
				)
			)
		)
		(sheetname "M.2 key M #1")
		(sheetfile "m2keym_low.kicad_sch")
		(solder_paste_margin_ratio -1)
		(attr smd)
		(fp_circle
			(center 0 0)
			(end 3.05 0)
			(stroke
				(width 0.05)
				(type solid)
			)
			(fill no)
			(layer "F.CrtYd")
		)
		(fp_circle
			(center 0 0)
			(end 2.6 0)
			(stroke
				(width 0.15)
				(type solid)
			)
			(fill no)
			(layer "F.Fab")
		)
		(pad "" smd custom
			(at -1.7 -1.7)
			(size 0.62 0.62)
			(layers "F.Paste")
			(thermal_bridge_angle 90)
			(options
				(clearance outline)
				(anchor circle)
			)
			(primitives
				(gr_arc
					(start -0.250195 1.279127)
					(mid 0.285453 0.294389)
					(end 1.266786 -0.24747)
					(width 0.2)
				)
				(gr_arc
					(start -0.34334 1.279127)
					(mid 0.218448 0.232561)
					(end 1.259603 -0.339191)
					(width 0.2)
				)
				(gr_arc
					(start -0.436309 1.279127)
					(mid 0.152481 0.169693)
					(end 1.255279 -0.431435)
					(width 0.2)
				)
				(gr_arc
					(start -0.529126 1.279127)
					(mid 0.087542 0.105784)
					(end 1.253811 -0.524161)
					(width 0.2)
				)
				(gr_arc
					(start -0.621807 1.279127)
					(mid 0.0309 0.033527)
					(end 1.275473 -0.621136)
					(width 0.2)
				)
				(gr_arc
					(start -0.71437 1.279127)
					(mid -0.037758 -0.026651)
					(end 1.263664 -0.711602)
					(width 0.2)
				)
				(gr_arc
					(start -0.806826 1.279127)
					(mid -0.105837 -0.087395)
					(end 1.253435 -0.802342)
					(width 0.2)
				)
				(gr_arc
					(start -0.899187 1.279127)
					(mid -0.165236 -0.156885)
					(end 1.267475 -0.897258)
					(width 0.2)
				)
				(gr_arc
					(start -0.991463 1.279127)
					(mid -0.228522 -0.222449)
					(end 1.270645 -0.990112)
					(width 0.2)
				)
				(gr_arc
					(start -1.083663 1.279127)
					(mid -0.294507 -0.285313)
					(end 1.266278 -1.081674)
					(width 0.2)
				)
				(gr_line
					(start 1.279127 -0.250195)
					(end 1.279127 -1.083663)
					(width 0.2)
				)
				(gr_line
					(start -0.250195 1.279127)
					(end -1.083663 1.279127)
					(width 0.2)
				)
			)
			(teardrops
				(best_length_ratio 0.2)
				(max_length 1)
				(best_width_ratio 0.9)
				(max_width 2)
				(curved_edges yes)
				(filter_ratio 0.9)
				(enabled yes)
				(allow_two_segments yes)
				(prefer_zone_connections yes)
			)
		)
		(pad "" smd custom
			(at -1.7 1.7 90)
			(size 0.62 0.62)
			(layers "F.Paste")
			(thermal_bridge_angle 90)
			(options
				(clearance outline)
				(anchor circle)
			)
			(primitives
				(gr_arc
					(start -0.250195 1.279127)
					(mid 0.285453 0.294389)
					(end 1.266786 -0.24747)
					(width 0.2)
				)
				(gr_arc
					(start -0.34334 1.279127)
					(mid 0.218448 0.232561)
					(end 1.259603 -0.339191)
					(width 0.2)
				)
				(gr_arc
					(start -0.436309 1.279127)
					(mid 0.152481 0.169693)
					(end 1.255279 -0.431435)
					(width 0.2)
				)
				(gr_arc
					(start -0.529126 1.279127)
					(mid 0.087542 0.105784)
					(end 1.253811 -0.524161)
					(width 0.2)
				)
				(gr_arc
					(start -0.621807 1.279127)
					(mid 0.0309 0.033527)
					(end 1.275473 -0.621136)
					(width 0.2)
				)
				(gr_arc
					(start -0.71437 1.279127)
					(mid -0.037758 -0.026651)
					(end 1.263664 -0.711602)
					(width 0.2)
				)
				(gr_arc
					(start -0.806826 1.279127)
					(mid -0.105837 -0.087395)
					(end 1.253435 -0.802342)
					(width 0.2)
				)
				(gr_arc
					(start -0.899187 1.279127)
					(mid -0.165236 -0.156885)
					(end 1.267475 -0.897258)
					(width 0.2)
				)
				(gr_arc
					(start -0.991463 1.279127)
					(mid -0.228522 -0.222449)
					(end 1.270645 -0.990112)
					(width 0.2)
				)
				(gr_arc
					(start -1.083663 1.279127)
					(mid -0.294507 -0.285313)
					(end 1.266278 -1.081674)
					(width 0.2)
				)
				(gr_line
					(start 1.279127 -0.250195)
					(end 1.279127 -1.083663)
					(width 0.2)
				)
				(gr_line
					(start -0.250195 1.279127)
					(end -1.083663 1.279127)
					(width 0.2)
				)
			)
			(teardrops
				(best_length_ratio 0.2)
				(max_length 1)
				(best_width_ratio 0.9)
				(max_width 2)
				(curved_edges yes)
				(filter_ratio 0.9)
				(enabled yes)
				(allow_two_segments yes)
				(prefer_zone_connections yes)
			)
		)
		(pad "" smd custom
			(at 1.7 -1.7 270)
			(size 0.62 0.62)
			(layers "F.Paste")
			(thermal_bridge_angle 90)
			(options
				(clearance outline)
				(anchor circle)
			)
			(primitives
				(gr_arc
					(start -0.250195 1.279127)
					(mid 0.285453 0.294389)
					(end 1.266786 -0.24747)
					(width 0.2)
				)
				(gr_arc
					(start -0.34334 1.279127)
					(mid 0.218448 0.232561)
					(end 1.259603 -0.339191)
					(width 0.2)
				)
				(gr_arc
					(start -0.436309 1.279127)
					(mid 0.152481 0.169693)
					(end 1.255279 -0.431435)
					(width 0.2)
				)
				(gr_arc
					(start -0.529126 1.279127)
					(mid 0.087542 0.105784)
					(end 1.253811 -0.524161)
					(width 0.2)
				)
				(gr_arc
					(start -0.621807 1.279127)
					(mid 0.0309 0.033527)
					(end 1.275473 -0.621136)
					(width 0.2)
				)
				(gr_arc
					(start -0.71437 1.279127)
					(mid -0.037758 -0.026651)
					(end 1.263664 -0.711602)
					(width 0.2)
				)
				(gr_arc
					(start -0.806826 1.279127)
					(mid -0.105837 -0.087395)
					(end 1.253435 -0.802342)
					(width 0.2)
				)
				(gr_arc
					(start -0.899187 1.279127)
					(mid -0.165236 -0.156885)
					(end 1.267475 -0.897258)
					(width 0.2)
				)
				(gr_arc
					(start -0.991463 1.279127)
					(mid -0.228522 -0.222449)
					(end 1.270645 -0.990112)
					(width 0.2)
				)
				(gr_arc
					(start -1.083663 1.279127)
					(mid -0.294507 -0.285313)
					(end 1.266278 -1.081674)
					(width 0.2)
				)
				(gr_line
					(start 1.279127 -0.250195)
					(end 1.279127 -1.083663)
					(width 0.2)
				)
				(gr_line
					(start -0.250195 1.279127)
					(end -1.083663 1.279127)
					(width 0.2)
				)
			)
			(teardrops
				(best_length_ratio 0.2)
				(max_length 1)
				(best_width_ratio 0.9)
				(max_width 2)
				(curved_edges yes)
				(filter_ratio 0.9)
				(enabled yes)
				(allow_two_segments yes)
				(prefer_zone_connections yes)
			)
		)
		(pad "" smd custom
			(at 1.7 1.7 180)
			(size 0.62 0.62)
			(layers "F.Paste")
			(thermal_bridge_angle 90)
			(options
				(clearance outline)
				(anchor circle)
			)
			(primitives
				(gr_arc
					(start -0.250195 1.279127)
					(mid 0.285453 0.294389)
					(end 1.266786 -0.24747)
					(width 0.2)
				)
				(gr_arc
					(start -0.34334 1.279127)
					(mid 0.218448 0.232561)
					(end 1.259603 -0.339191)
					(width 0.2)
				)
				(gr_arc
					(start -0.436309 1.279127)
					(mid 0.152481 0.169693)
					(end 1.255279 -0.431435)
					(width 0.2)
				)
				(gr_arc
					(start -0.529126 1.279127)
					(mid 0.087542 0.105784)
					(end 1.253811 -0.524161)
					(width 0.2)
				)
				(gr_arc
					(start -0.621807 1.279127)
					(mid 0.0309 0.033527)
					(end 1.275473 -0.621136)
					(width 0.2)
				)
				(gr_arc
					(start -0.71437 1.279127)
					(mid -0.037758 -0.026651)
					(end 1.263664 -0.711602)
					(width 0.2)
				)
				(gr_arc
					(start -0.806826 1.279127)
					(mid -0.105837 -0.087395)
					(end 1.253435 -0.802342)
					(width 0.2)
				)
				(gr_arc
					(start -0.899187 1.279127)
					(mid -0.165236 -0.156885)
					(end 1.267475 -0.897258)
					(width 0.2)
				)
				(gr_arc
					(start -0.991463 1.279127)
					(mid -0.228522 -0.222449)
					(end 1.270645 -0.990112)
					(width 0.2)
				)
				(gr_arc
					(start -1.083663 1.279127)
					(mid -0.294507 -0.285313)
					(end 1.266278 -1.081674)
					(width 0.2)
				)
				(gr_line
					(start 1.279127 -0.250195)
					(end 1.279127 -1.083663)
					(width 0.2)
				)
				(gr_line
					(start -0.250195 1.279127)
					(end -1.083663 1.279127)
					(width 0.2)
				)
			)
			(teardrops
				(best_length_ratio 0.2)
				(max_length 1)
				(best_width_ratio 0.9)
				(max_width 2)
				(curved_edges yes)
				(filter_ratio 0.9)
				(enabled yes)
				(allow_two_segments yes)
				(prefer_zone_connections yes)
			)
		)
		(pad "1" thru_hole circle
			(at 0 0)
			(size 6 6)
			(drill 3.7)
			(layers "*.Cu" "*.Mask")
			(remove_unused_layers no)
			(net 1 "GND")
			(pintype "passive")
			(teardrops
				(best_length_ratio 0.4)
				(max_length 1)
				(best_width_ratio 0.9)
				(max_width 2)
				(curved_edges yes)
				(filter_ratio 0.9)
				(enabled yes)
				(allow_two_segments yes)
				(prefer_zone_connections yes)
			)
		)
	)
	(footprint "antmicro-footprints:C_0402_1005Metric"
		(layer "F.Cu")
		(at 143 140.86)
		(descr "Capacitor SMD 0402")
		(tags "capacitor SMD 0402")
		(property "Reference" "C151"
			(at -3.55 0.4 0)
			(layer "F.SilkS")
			(effects
				(font
					(size 0.7 0.7)
					(thickness 0.15)
				)
				(justify left bottom)
			)
		)
		(property "Value" "C_100n_0402"
			(at -1.022927 2.155213 0)
			(layer "F.Fab")
			(effects
				(font
					(size 0.7 0.7)
					(thickness 0.15)
				)
				(justify left bottom)
			)
		)
		(property "Datasheet" "https://www.murata.com/products/productdetail?partno=GRM155R61H104KE14%23"
			(at 0 0 0)
			(layer "F.Fab")
			(hide yes)
			(effects
				(font
					(size 1.27 1.27)
					(thickness 0.15)
				)
			)
		)
		(property "Author" "Antmicro"
			(at 0 0 0)
			(layer "F.Fab")
			(hide yes)
			(effects
				(font
					(size 1 1)
					(thickness 0.15)
				)
			)
		)
		(property "Dielectric" "X5R"
			(at 0 0 0)
			(layer "F.Fab")
			(hide yes)
			(effects
				(font
					(size 1 1)
					(thickness 0.15)
				)
			)
		)
		(property "License" "Apache-2.0"
			(at 0 0 0)
			(layer "F.Fab")
			(hide yes)
			(effects
				(font
					(size 1 1)
					(thickness 0.15)
				)
			)
		)
		(property "MPN" "GRM155R61H104KE14D"
			(at 0 0 0)
			(layer "F.Fab")
			(hide yes)
			(effects
				(font
					(size 1 1)
					(thickness 0.15)
				)
			)
		)
		(property "Manufacturer" "Murata"
			(at 0 0 0)
			(layer "F.Fab")
			(hide yes)
			(effects
				(font
					(size 1 1)
					(thickness 0.15)
				)
			)
		)
		(property "Public" "False"
			(at 0 0 0)
			(layer "F.Fab")
			(hide yes)
			(effects
				(font
					(size 1 1)
					(thickness 0.15)
				)
			)
		)
		(property "Val" "100n"
			(at 0 0 0)
			(layer "F.Fab")
			(hide yes)
			(effects
				(font
					(size 1 1)
					(thickness 0.15)
				)
			)
		)
		(property "Voltage" "50V"
			(at 0 0 0)
			(layer "F.Fab")
			(hide yes)
			(effects
				(font
					(size 1 1)
					(thickness 0.15)
				)
			)
		)
		(sheetname "KR to SFI #1")
		(sheetfile "kr_sfi.kicad_sch")
		(attr smd)
		(fp_rect
			(start -0.925 -0.47)
			(end 0.925 0.47)
			(stroke
				(width 0.05)
				(type default)
			)
			(fill no)
			(layer "F.CrtYd")
		)
		(fp_line
			(start -0.494 -0.25)
			(end 0.504 -0.25)
			(stroke
				(width 0.15)
				(type solid)
			)
			(layer "F.Fab")
		)
		(fp_line
			(start -0.494 0.248)
			(end -0.494 -0.25)
			(stroke
				(width 0.15)
				(type solid)
			)
			(layer "F.Fab")
		)
		(fp_line
			(start 0.504 -0.25)
			(end 0.504 0.248)
			(stroke
				(width 0.15)
				(type solid)
			)
			(layer "F.Fab")
		)
		(fp_line
			(start 0.504 0.248)
			(end -0.494 0.248)
			(stroke
				(width 0.15)
				(type solid)
			)
			(layer "F.Fab")
		)
		(pad "1" smd roundrect
			(at -0.48 0)
			(size 0.59 0.64)
			(layers "F.Cu" "F.Mask" "F.Paste")
			(roundrect_rratio 0.25)
			(net 109 "/2xSFP+/KR to SFI #1/CLK-")
			(pintype "passive")
			(teardrops
				(best_length_ratio 0.2)
				(max_length 1)
				(best_width_ratio 0.9)
				(max_width 2)
				(curved_edges yes)
				(filter_ratio 0.9)
				(enabled yes)
				(allow_two_segments yes)
				(prefer_zone_connections yes)
			)
		)
		(pad "2" smd roundrect
			(at 0.48 0)
			(size 0.59 0.64)
			(layers "F.Cu" "F.Mask" "F.Paste")
			(roundrect_rratio 0.25)
			(net 108 "/2xSFP+/KR to SFI #1/REFCLK+")
			(pintype "passive")
			(teardrops
				(best_length_ratio 0.2)
				(max_length 1)
				(best_width_ratio 0.9)
				(max_width 2)
				(curved_edges yes)
				(filter_ratio 0.9)
				(enabled yes)
				(allow_two_segments yes)
				(prefer_zone_connections yes)
			)
		)
	)
	(footprint "antmicro-footprints:R_0201"
		(layer "F.Cu")
		(at 134.41 147.935 -90)
		(descr "Resistor SMD 0201")
		(tags "resistor SMD 0201")
		(property "Reference" "R284"
			(at 6.475 -0.29 270)
			(layer "F.SilkS")
			(effects
				(font
					(size 0.7 0.7)
					(thickness 0.15)
				)
				(justify left bottom)
			)
		)
		(property "Value" "R_0R_0201"
			(at 0 1.25 270)
			(layer "F.Fab")
			(effects
				(font
					(size 0.7 0.7)
					(thickness 0.15)
				)
				(justify left bottom)
			)
		)
		(property "Datasheet" "https://www.bourns.com/docs/product-datasheets/cr.pdf"
			(at 0 0 270)
			(layer "F.Fab")
			(hide yes)
			(effects
				(font
					(size 1.27 1.27)
					(thickness 0.15)
				)
			)
		)
		(property "Author" "Antmicro"
			(at -13.525 282.345 0)
			(layer "F.Fab")
			(hide yes)
			(effects
				(font
					(size 1 1)
					(thickness 0.15)
				)
			)
		)
		(property "License" "Apache-2.0"
			(at -13.525 282.345 0)
			(layer "F.Fab")
			(hide yes)
			(effects
				(font
					(size 1 1)
					(thickness 0.15)
				)
			)
		)
		(property "MPN" "CR0201-FX-0R00GLF"
			(at -13.525 282.345 0)
			(layer "F.Fab")
			(hide yes)
			(effects
				(font
					(size 1 1)
					(thickness 0.15)
				)
			)
		)
		(property "Manufacturer" "Bourns"
			(at -13.525 282.345 0)
			(layer "F.Fab")
			(hide yes)
			(effects
				(font
					(size 1 1)
					(thickness 0.15)
				)
			)
		)
		(property "Tolerance" "1%"
			(at -13.525 282.345 0)
			(layer "F.Fab")
			(hide yes)
			(effects
				(font
					(size 1 1)
					(thickness 0.15)
				)
			)
		)
		(property "Val" "0R"
			(at -13.525 282.345 0)
			(layer "F.Fab")
			(hide yes)
			(effects
				(font
					(size 1 1)
					(thickness 0.15)
				)
			)
		)
		(sheetname "KR to SFI #2")
		(sheetfile "kr_sfi.kicad_sch")
		(attr smd dnp)
		(fp_rect
			(start -0.7 -0.35)
			(end 0.7 0.35)
			(stroke
				(width 0.05)
				(type default)
			)
			(fill no)
			(layer "F.CrtYd")
		)
		(fp_rect
			(start -0.3 -0.15)
			(end 0.298 0.148)
			(stroke
				(width 0.15)
				(type solid)
			)
			(fill no)
			(layer "F.Fab")
		)
		(pad "" smd roundrect
			(at -0.346 0 270)
			(size 0.318 0.36)
			(layers "F.Paste")
			(roundrect_rratio 0.25)
			(teardrops
				(best_length_ratio 0.2)
				(max_length 1)
				(best_width_ratio 0.9)
				(max_width 2)
				(curved_edges yes)
				(filter_ratio 0.9)
				(enabled yes)
				(allow_two_segments yes)
				(prefer_zone_connections yes)
			)
		)
		(pad "" smd roundrect
			(at 0.344 0 270)
			(size 0.318 0.36)
			(layers "F.Paste")
			(roundrect_rratio 0.25)
			(teardrops
				(best_length_ratio 0.2)
				(max_length 1)
				(best_width_ratio 0.9)
				(max_width 2)
				(curved_edges yes)
				(filter_ratio 0.9)
				(enabled yes)
				(allow_two_segments yes)
				(prefer_zone_connections yes)
			)
		)
		(pad "1" smd roundrect
			(at -0.32 0 270)
			(size 0.46 0.4)
			(layers "F.Cu" "F.Mask")
			(roundrect_rratio 0.25)
			(net 428 "/2xSFP+/10GKR_SFP1.RX-")
			(pintype "passive")
			(teardrops
				(best_length_ratio 0.2)
				(max_length 1)
				(best_width_ratio 0.9)
				(max_width 2)
				(curved_edges yes)
				(filter_ratio 0.9)
				(enabled yes)
				(allow_two_segments yes)
				(prefer_zone_connections yes)
			)
		)
		(pad "2" smd roundrect
			(at 0.32 0 270)
			(size 0.46 0.4)
			(layers "F.Cu" "F.Mask")
			(roundrect_rratio 0.25)
			(net 968 "/2xSFP+/KR to SFI #2/BYP_RX-")
			(pintype "passive")
			(teardrops
				(best_length_ratio 0.2)
				(max_length 1)
				(best_width_ratio 0.9)
				(max_width 2)
				(curved_edges yes)
				(filter_ratio 0.9)
				(enabled yes)
				(allow_two_segments yes)
				(prefer_zone_connections yes)
			)
		)
	)
)
